(kicad_pcb
	(version 20260206)
	(generator "pcbnew")
	(generator_version "10.0")
	(general
		(thickness 1.6)
		(legacy_teardrops no)
	)
	(paper "A4")
	(title_block
		(title "v1-pdb — T6M_PDB_D_0927_0900.brd")
		(comment 1 "Open CloudServer (Microsoft) / footprints 66-75 of 321")
	)
	(layers
		(0 "F.Cu" signal "TOP")
		(4 "In1.Cu" signal "GND")
		(6 "In2.Cu" signal "IN1")
		(8 "In3.Cu" signal "VCC")
		(10 "In4.Cu" signal "VCC1")
		(12 "In5.Cu" signal "IN2")
		(14 "In6.Cu" signal "GND1")
		(2 "B.Cu" signal "BOTTOM")
		(9 "F.Adhes" user "F.Adhesive")
		(11 "B.Adhes" user "B.Adhesive")
		(13 "F.Paste" user "Package Geometry/Pastemask Top")
		(15 "B.Paste" user "Package Geometry/Pastemask Bottom")
		(5 "F.SilkS" user "Ref Des/Silkscreen Top")
		(7 "B.SilkS" user "Ref Des/Silkscreen Bottom")
		(1 "F.Mask" user "Board Geometry/Soldermask Top")
		(3 "B.Mask" user "Board Geometry/Soldermask Bottom")
		(17 "Dwgs.User" user "User.Drawings")
		(19 "Cmts.User" user "User.Comments")
		(21 "Eco1.User" user "User.Eco1")
		(23 "Eco2.User" user "User.Eco2")
		(25 "Edge.Cuts" user "Board Geometry/Outline")
		(27 "Margin" user)
		(31 "F.CrtYd" user "Package Geometry/Place Bound Top")
		(29 "B.CrtYd" user "Package Geometry/Place Bound Bottom")
		(35 "F.Fab" user "Ref Des/Assembly Top")
		(33 "B.Fab" user "Ref Des/Assembly Bottom")
	)
	(footprint ""
		(layer "F.Cu")
		(at 39.934642 -374.14708)
		(property "Reference" "R44"
			(at 2.011172 0.405638 0)
			(unlocked yes)
			(layer "F.SilkS")
			(effects
				(font
					(size 0.7874 0.5842)
					(thickness 0.1524)
				)
				(justify left)
			)
		)
		(property "Value" ""
			(at 0 0 0)
			(layer "F.Fab")
			(effects
				(font
					(size 1.27 1.27)
				)
			)
		)
		(duplicate_pad_numbers_are_jumpers no)
		(fp_line
			(start -0.7874 -0.4064)
			(end 0.7874 -0.4064)
			(stroke
				(width 0.1524)
				(type default)
			)
			(layer "F.SilkS")
		)
		(fp_line
			(start -0.7874 0.4064)
			(end -0.7874 -0.4064)
			(stroke
				(width 0.1524)
				(type default)
			)
			(layer "F.SilkS")
		)
		(fp_line
			(start 0.7874 -0.4064)
			(end 0.7874 0.4064)
			(stroke
				(width 0.1524)
				(type default)
			)
			(layer "F.SilkS")
		)
		(fp_line
			(start 0.7874 0.4064)
			(end -0.7874 0.4064)
			(stroke
				(width 0.1524)
				(type default)
			)
			(layer "F.SilkS")
		)
		(fp_poly
			(pts
				(xy -0.508 0.2794) (xy -0.508 0.2286) (xy -0.635 0.2286) (xy -0.635 -0.254) (xy -0.5334 -0.254)
				(xy -0.5334 -0.2794) (xy 0.5334 -0.2794) (xy 0.5334 -0.254) (xy 0.635 -0.254) (xy 0.635 0.254) (xy 0.5334 0.254)
				(xy 0.5334 0.2794)
			)
			(stroke
				(width 0)
				(type default)
			)
			(fill no)
			(layer "F.CrtYd")
		)
		(pad "1" smd rect
			(at 0.40005 0)
			(size 0.4572 0.508)
			(layers "F.Cu" "F.Mask" "F.Paste")
			(net "GND")
		)
		(pad "2" smd rect
			(at -0.40005 0)
			(size 0.4572 0.508)
			(layers "F.Cu" "F.Mask" "F.Paste")
			(net "P12V_STBY")
		)
	)
	(footprint ""
		(layer "F.Cu")
		(at 73.909936 -149.113748 -90)
		(property "Reference" "C23"
			(at -2.638552 0.124206 90)
			(unlocked yes)
			(layer "F.SilkS")
			(effects
				(font
					(size 0.7874 0.5842)
					(thickness 0.1524)
				)
				(justify left)
			)
		)
		(property "Value" ""
			(at 0 0 270)
			(layer "F.Fab")
			(effects
				(font
					(size 1.27 1.27)
				)
			)
		)
		(duplicate_pad_numbers_are_jumpers no)
		(fp_line
			(start -0.7874 0.4064)
			(end -0.7874 -0.4064)
			(stroke
				(width 0.1524)
				(type default)
			)
			(layer "F.SilkS")
		)
		(fp_line
			(start 0.7874 0.4064)
			(end -0.7874 0.4064)
			(stroke
				(width 0.1524)
				(type default)
			)
			(layer "F.SilkS")
		)
		(fp_line
			(start 0 0.381)
			(end 0 -0.381)
			(stroke
				(width 0.1524)
				(type default)
			)
			(layer "F.SilkS")
		)
		(fp_line
			(start -0.7874 -0.4064)
			(end 0.7874 -0.4064)
			(stroke
				(width 0.1524)
				(type default)
			)
			(layer "F.SilkS")
		)
		(fp_line
			(start 0.7874 -0.4064)
			(end 0.7874 0.4064)
			(stroke
				(width 0.1524)
				(type default)
			)
			(layer "F.SilkS")
		)
		(fp_poly
			(pts
				(xy -0.5334 0.254) (xy -0.635 0.254) (xy -0.635 0.2286) (xy -0.635 -0.254) (xy -0.5334 -0.254) (xy -0.5334 -0.2794)
				(xy 0.5334 -0.2794) (xy 0.5334 -0.254) (xy 0.635 -0.254) (xy 0.635 0.254) (xy 0.5334 0.254) (xy 0.5334 0.2794)
				(xy -0.508 0.2794) (xy -0.5334 0.2794)
			)
			(stroke
				(width 0)
				(type default)
			)
			(fill no)
			(layer "F.CrtYd")
		)
		(pad "1" smd rect
			(at 0.40005 0 270)
			(size 0.4572 0.508)
			(layers "F.Cu" "F.Mask" "F.Paste")
			(net "P12V")
		)
		(pad "2" smd rect
			(at -0.40005 0 270)
			(size 0.4572 0.508)
			(layers "F.Cu" "F.Mask" "F.Paste")
			(net "GND")
		)
	)
	(footprint ""
		(layer "F.Cu")
		(at 91.399868 -108.909866)
		(property "Reference" "H17"
			(at -5.1308 -5.23113 0)
			(unlocked yes)
			(layer "F.SilkS")
			(effects
				(font
					(size 0.7874 0.5842)
					(thickness 0.1524)
				)
				(justify left)
			)
		)
		(property "Value" ""
			(at 0 0 0)
			(layer "F.Fab")
			(effects
				(font
					(size 1.27 1.27)
				)
			)
		)
		(duplicate_pad_numbers_are_jumpers no)
		(fp_circle
			(center 0 0)
			(end 4.826 0)
			(stroke
				(width 0.1524)
				(type default)
			)
			(fill no)
			(layer "F.SilkS")
		)
		(fp_circle
			(center 0 0)
			(end 4.826 0)
			(stroke
				(width 0.1524)
				(type default)
			)
			(fill no)
			(layer "B.SilkS")
		)
		(fp_poly
			(pts
				(arc
					(start 0 4.0132)
					(mid 0 -4.0132)
					(end 0 4.0132)
				)
			)
			(stroke
				(width 0)
				(type default)
			)
			(fill no)
			(layer "F.CrtYd")
		)
		(pad "" np_thru_hole circle
			(at 0 0)
			(size 8.001 8.001)
			(drill 8.001)
			(layers "*.Cu" "*.Mask")
			(clearance 0.381)
			(thermal_gap 0.381)
		)
		(zone
			(layers "F.Cu" "B.Cu" "In1.Cu" "In2.Cu" "In3.Cu" "In4.Cu" "In5.Cu" "In6.Cu")
			(hatch none 0.5)
			(connect_pads
				(clearance 0)
			)
			(min_thickness 0.25)
			(keepout
				(tracks not_allowed)
				(vias allowed)
				(pads allowed)
				(copperpour not_allowed)
				(footprints allowed)
			)
			(placement
				(enabled no)
				(sheetname "")
			)
			(fill
				(thermal_gap 0.5)
				(thermal_bridge_width 0.5)
				(island_removal_mode 0)
			)
			(polygon
				(pts
					(arc
						(start 91.399868 -104.388666)
						(mid 91.399868 -113.431066)
						(end 91.399868 -104.388666)
					)
				)
			)
		)
	)
	(footprint ""
		(layer "F.Cu")
		(at 68.639436 -371.109748 -90)
		(property "Reference" "C57"
			(at -3.246628 0.156972 90)
			(unlocked yes)
			(layer "F.SilkS")
			(effects
				(font
					(size 0.7874 0.5842)
					(thickness 0.1524)
				)
			)
		)
		(property "Value" ""
			(at 0 0 270)
			(layer "F.Fab")
			(effects
				(font
					(size 1.27 1.27)
				)
			)
		)
		(duplicate_pad_numbers_are_jumpers no)
		(fp_line
			(start -1.2954 0.5842)
			(end -1.2954 -0.5842)
			(stroke
				(width 0.1524)
				(type default)
			)
			(layer "F.SilkS")
		)
		(fp_line
			(start 1.2954 0.5842)
			(end -1.2954 0.5842)
			(stroke
				(width 0.1524)
				(type default)
			)
			(layer "F.SilkS")
		)
		(fp_line
			(start -1.2954 -0.5842)
			(end 1.2954 -0.5842)
			(stroke
				(width 0.1524)
				(type default)
			)
			(layer "F.SilkS")
		)
		(fp_line
			(start 0 -0.5842)
			(end 0 0.5842)
			(stroke
				(width 0.1524)
				(type default)
			)
			(layer "F.SilkS")
		)
		(fp_line
			(start 1.2954 -0.5842)
			(end 1.2954 0.5842)
			(stroke
				(width 0.1524)
				(type default)
			)
			(layer "F.SilkS")
		)
		(fp_poly
			(pts
				(xy 0.8636 -0.4572) (xy 0.8636 -0.3556) (xy 1.143 -0.3556) (xy 1.143 0.3556) (xy 0.8636 0.3556)
				(xy 0.8636 0.4572) (xy -0.8636 0.4572) (xy -0.8636 0.3556) (xy -1.143 0.3556) (xy -1.143 -0.3556)
				(xy -0.8636 -0.3556) (xy -0.8636 -0.4572)
			)
			(stroke
				(width 0)
				(type default)
			)
			(fill no)
			(layer "F.CrtYd")
		)
		(fp_line
			(start -0.884936 0.504952)
			(end -0.884936 -0.504952)
			(stroke
				(width 0.1)
				(type default)
			)
			(layer "F.Fab")
		)
		(fp_line
			(start 0.884936 0.504952)
			(end -0.884936 0.504952)
			(stroke
				(width 0.1)
				(type default)
			)
			(layer "F.Fab")
		)
		(fp_line
			(start -0.884936 -0.504952)
			(end 0.884936 -0.504952)
			(stroke
				(width 0.1)
				(type default)
			)
			(layer "F.Fab")
		)
		(fp_line
			(start 0.884936 -0.504952)
			(end 0.884936 0.504952)
			(stroke
				(width 0.1)
				(type default)
			)
			(layer "F.Fab")
		)
		(pad "1" smd rect
			(at 0.7366 0)
			(size 0.7112 0.8128)
			(layers "F.Cu" "F.Mask" "F.Paste")
			(net "P12V")
		)
		(pad "2" smd rect
			(at -0.7366 0)
			(size 0.7112 0.8128)
			(layers "F.Cu" "F.Mask" "F.Paste")
			(net "GND")
		)
	)
	(footprint ""
		(layer "F.Cu")
		(at 70.278244 -220.425772 90)
		(property "Reference" "C41"
			(at -3.909568 -0.209296 90)
			(unlocked yes)
			(layer "F.SilkS")
			(effects
				(font
					(size 0.7874 0.5842)
					(thickness 0.1524)
				)
				(justify left)
			)
		)
		(property "Value" ""
			(at 0 0 90)
			(layer "F.Fab")
			(effects
				(font
					(size 1.27 1.27)
				)
			)
		)
		(duplicate_pad_numbers_are_jumpers no)
		(fp_line
			(start 0.7874 -0.4064)
			(end 0.7874 0.4064)
			(stroke
				(width 0.1524)
				(type default)
			)
			(layer "F.SilkS")
		)
		(fp_line
			(start -0.7874 -0.4064)
			(end 0.7874 -0.4064)
			(stroke
				(width 0.1524)
				(type default)
			)
			(layer "F.SilkS")
		)
		(fp_line
			(start 0 0.381)
			(end 0 -0.381)
			(stroke
				(width 0.1524)
				(type default)
			)
			(layer "F.SilkS")
		)
		(fp_line
			(start 0.7874 0.4064)
			(end -0.7874 0.4064)
			(stroke
				(width 0.1524)
				(type default)
			)
			(layer "F.SilkS")
		)
		(fp_line
			(start -0.7874 0.4064)
			(end -0.7874 -0.4064)
			(stroke
				(width 0.1524)
				(type default)
			)
			(layer "F.SilkS")
		)
		(fp_poly
			(pts
				(xy -0.5334 0.254) (xy -0.635 0.254) (xy -0.635 0.2286) (xy -0.635 -0.254) (xy -0.5334 -0.254) (xy -0.5334 -0.2794)
				(xy 0.5334 -0.2794) (xy 0.5334 -0.254) (xy 0.635 -0.254) (xy 0.635 0.254) (xy 0.5334 0.254) (xy 0.5334 0.2794)
				(xy -0.508 0.2794) (xy -0.5334 0.2794)
			)
			(stroke
				(width 0)
				(type default)
			)
			(fill no)
			(layer "F.CrtYd")
		)
		(pad "1" smd rect
			(at 0.40005 0 90)
			(size 0.4572 0.508)
			(layers "F.Cu" "F.Mask" "F.Paste")
			(net "P12V")
		)
		(pad "2" smd rect
			(at -0.40005 0 90)
			(size 0.4572 0.508)
			(layers "F.Cu" "F.Mask" "F.Paste")
			(net "GND")
		)
	)
	(footprint ""
		(layer "F.Cu")
		(at 39.90086 -194.114674 180)
		(property "Reference" "R13"
			(at -1.710182 -0.085344 0)
			(unlocked yes)
			(layer "F.SilkS")
			(effects
				(font
					(size 0.7874 0.5842)
					(thickness 0.1524)
				)
				(justify left)
			)
		)
		(property "Value" ""
			(at 0 0 180)
			(layer "F.Fab")
			(effects
				(font
					(size 1.27 1.27)
				)
			)
		)
		(duplicate_pad_numbers_are_jumpers no)
		(fp_line
			(start 0.7874 0.4064)
			(end -0.7874 0.4064)
			(stroke
				(width 0.1524)
				(type default)
			)
			(layer "F.SilkS")
		)
		(fp_line
			(start 0.7874 -0.4064)
			(end 0.7874 0.4064)
			(stroke
				(width 0.1524)
				(type default)
			)
			(layer "F.SilkS")
		)
		(fp_line
			(start -0.7874 0.4064)
			(end -0.7874 -0.4064)
			(stroke
				(width 0.1524)
				(type default)
			)
			(layer "F.SilkS")
		)
		(fp_line
			(start -0.7874 -0.4064)
			(end 0.7874 -0.4064)
			(stroke
				(width 0.1524)
				(type default)
			)
			(layer "F.SilkS")
		)
		(fp_poly
			(pts
				(xy -0.508 0.2794) (xy -0.508 0.2286) (xy -0.635 0.2286) (xy -0.635 -0.254) (xy -0.5334 -0.254)
				(xy -0.5334 -0.2794) (xy 0.5334 -0.2794) (xy 0.5334 -0.254) (xy 0.635 -0.254) (xy 0.635 0.254) (xy 0.5334 0.254)
				(xy 0.5334 0.2794)
			)
			(stroke
				(width 0)
				(type default)
			)
			(fill no)
			(layer "F.CrtYd")
		)
		(pad "1" smd rect
			(at 0.40005 0 180)
			(size 0.4572 0.508)
			(layers "F.Cu" "F.Mask" "F.Paste")
			(net "PSU3_AD0")
		)
		(pad "2" smd rect
			(at -0.40005 0 180)
			(size 0.4572 0.508)
			(layers "F.Cu" "F.Mask" "F.Paste")
			(net "GND")
		)
	)
	(footprint ""
		(layer "F.Cu")
		(at 68.716144 -117.627146 180)
		(property "Reference" "R116"
			(at 1.552448 -1.398016 0)
			(unlocked yes)
			(layer "F.SilkS")
			(effects
				(font
					(size 0.7874 0.5842)
					(thickness 0.1524)
				)
				(justify left)
			)
		)
		(property "Value" ""
			(at 0 0 180)
			(layer "F.Fab")
			(effects
				(font
					(size 1.27 1.27)
				)
			)
		)
		(duplicate_pad_numbers_are_jumpers no)
		(fp_line
			(start 0.7874 0.4064)
			(end -0.7874 0.4064)
			(stroke
				(width 0.1524)
				(type default)
			)
			(layer "F.SilkS")
		)
		(fp_line
			(start 0.7874 -0.4064)
			(end 0.7874 0.4064)
			(stroke
				(width 0.1524)
				(type default)
			)
			(layer "F.SilkS")
		)
		(fp_line
			(start -0.7874 0.4064)
			(end -0.7874 -0.4064)
			(stroke
				(width 0.1524)
				(type default)
			)
			(layer "F.SilkS")
		)
		(fp_line
			(start -0.7874 -0.4064)
			(end 0.7874 -0.4064)
			(stroke
				(width 0.1524)
				(type default)
			)
			(layer "F.SilkS")
		)
		(fp_poly
			(pts
				(xy -0.508 0.2794) (xy -0.508 0.2286) (xy -0.635 0.2286) (xy -0.635 -0.254) (xy -0.5334 -0.254)
				(xy -0.5334 -0.2794) (xy 0.5334 -0.2794) (xy 0.5334 -0.254) (xy 0.635 -0.254) (xy 0.635 0.254) (xy 0.5334 0.254)
				(xy 0.5334 0.2794)
			)
			(stroke
				(width 0)
				(type default)
			)
			(fill no)
			(layer "F.CrtYd")
		)
		(pad "1" smd rect
			(at 0.40005 0 180)
			(size 0.4572 0.508)
			(layers "F.Cu" "F.Mask" "F.Paste")
			(net "PSU2_REMOTE_R2_N")
		)
		(pad "2" smd rect
			(at -0.40005 0 180)
			(size 0.4572 0.508)
			(layers "F.Cu" "F.Mask" "F.Paste")
			(net "GND")
		)
	)
	(footprint ""
		(layer "F.Cu")
		(at 39.460424 -198.769478 90)
		(property "Reference" "R118"
			(at -0.484632 1.99009 0)
			(unlocked yes)
			(layer "F.SilkS")
			(effects
				(font
					(size 0.7874 0.5842)
					(thickness 0.1524)
				)
				(justify left)
			)
		)
		(property "Value" ""
			(at 0 0 90)
			(layer "F.Fab")
			(effects
				(font
					(size 1.27 1.27)
				)
			)
		)
		(duplicate_pad_numbers_are_jumpers no)
		(fp_line
			(start 0.7874 -0.4064)
			(end 0.7874 0.4064)
			(stroke
				(width 0.1524)
				(type default)
			)
			(layer "F.SilkS")
		)
		(fp_line
			(start -0.7874 -0.4064)
			(end 0.7874 -0.4064)
			(stroke
				(width 0.1524)
				(type default)
			)
			(layer "F.SilkS")
		)
		(fp_line
			(start 0.7874 0.4064)
			(end -0.7874 0.4064)
			(stroke
				(width 0.1524)
				(type default)
			)
			(layer "F.SilkS")
		)
		(fp_line
			(start -0.7874 0.4064)
			(end -0.7874 -0.4064)
			(stroke
				(width 0.1524)
				(type default)
			)
			(layer "F.SilkS")
		)
		(fp_poly
			(pts
				(xy -0.508 0.2794) (xy -0.508 0.2286) (xy -0.635 0.2286) (xy -0.635 -0.254) (xy -0.5334 -0.254)
				(xy -0.5334 -0.2794) (xy 0.5334 -0.2794) (xy 0.5334 -0.254) (xy 0.635 -0.254) (xy 0.635 0.254) (xy 0.5334 0.254)
				(xy 0.5334 0.2794)
			)
			(stroke
				(width 0)
				(type default)
			)
			(fill no)
			(layer "F.CrtYd")
		)
		(pad "1" smd rect
			(at 0.40005 0 90)
			(size 0.4572 0.508)
			(layers "F.Cu" "F.Mask" "F.Paste")
			(net "PSU3_REMOTE_P")
		)
		(pad "2" smd rect
			(at -0.40005 0 90)
			(size 0.4572 0.508)
			(layers "F.Cu" "F.Mask" "F.Paste")
			(net "PSU3_REMOTE_R2_P")
		)
	)
	(footprint ""
		(layer "F.Cu")
		(at 27.577542 -373.832628 -90)
		(property "Reference" "R105"
			(at -1.488948 1.318514 90)
			(unlocked yes)
			(layer "F.SilkS")
			(effects
				(font
					(size 0.7874 0.5842)
					(thickness 0.1524)
				)
				(justify left)
			)
		)
		(property "Value" ""
			(at 0 0 270)
			(layer "F.Fab")
			(effects
				(font
					(size 1.27 1.27)
				)
			)
		)
		(duplicate_pad_numbers_are_jumpers no)
		(fp_line
			(start -0.7874 0.4064)
			(end -0.7874 -0.4064)
			(stroke
				(width 0.1524)
				(type default)
			)
			(layer "F.SilkS")
		)
		(fp_line
			(start 0.7874 0.4064)
			(end -0.7874 0.4064)
			(stroke
				(width 0.1524)
				(type default)
			)
			(layer "F.SilkS")
		)
		(fp_line
			(start -0.7874 -0.4064)
			(end 0.7874 -0.4064)
			(stroke
				(width 0.1524)
				(type default)
			)
			(layer "F.SilkS")
		)
		(fp_line
			(start 0.7874 -0.4064)
			(end 0.7874 0.4064)
			(stroke
				(width 0.1524)
				(type default)
			)
			(layer "F.SilkS")
		)
		(fp_poly
			(pts
				(xy -0.508 0.2794) (xy -0.508 0.2286) (xy -0.635 0.2286) (xy -0.635 -0.254) (xy -0.5334 -0.254)
				(xy -0.5334 -0.2794) (xy 0.5334 -0.2794) (xy 0.5334 -0.254) (xy 0.635 -0.254) (xy 0.635 0.254) (xy 0.5334 0.254)
				(xy 0.5334 0.2794)
			)
			(stroke
				(width 0)
				(type default)
			)
			(fill no)
			(layer "F.CrtYd")
		)
		(pad "1" smd rect
			(at 0.40005 0 270)
			(size 0.4572 0.508)
			(layers "F.Cu" "F.Mask" "F.Paste")
			(net "PSU5_REMOTE_N")
		)
		(pad "2" smd rect
			(at -0.40005 0 270)
			(size 0.4572 0.508)
			(layers "F.Cu" "F.Mask" "F.Paste")
			(net "PSU5_REMOTE_R_N")
		)
	)
	(footprint ""
		(layer "F.Cu")
		(at 66.82994 -32.569912 180)
		(property "Reference" "R111"
			(at 1.090422 -1.06934 0)
			(unlocked yes)
			(layer "F.SilkS")
			(effects
				(font
					(size 0.7874 0.5842)
					(thickness 0.1524)
				)
				(justify left)
			)
		)
		(property "Value" ""
			(at 0 0 180)
			(layer "F.Fab")
			(effects
				(font
					(size 1.27 1.27)
				)
			)
		)
		(duplicate_pad_numbers_are_jumpers no)
		(fp_line
			(start 0.7874 0.4064)
			(end -0.7874 0.4064)
			(stroke
				(width 0.1524)
				(type default)
			)
			(layer "F.SilkS")
		)
		(fp_line
			(start 0.7874 -0.4064)
			(end 0.7874 0.4064)
			(stroke
				(width 0.1524)
				(type default)
			)
			(layer "F.SilkS")
		)
		(fp_line
			(start -0.7874 0.4064)
			(end -0.7874 -0.4064)
			(stroke
				(width 0.1524)
				(type default)
			)
			(layer "F.SilkS")
		)
		(fp_line
			(start -0.7874 -0.4064)
			(end 0.7874 -0.4064)
			(stroke
				(width 0.1524)
				(type default)
			)
			(layer "F.SilkS")
		)
		(fp_poly
			(pts
				(xy -0.508 0.2794) (xy -0.508 0.2286) (xy -0.635 0.2286) (xy -0.635 -0.254) (xy -0.5334 -0.254)
				(xy -0.5334 -0.2794) (xy 0.5334 -0.2794) (xy 0.5334 -0.254) (xy 0.635 -0.254) (xy 0.635 0.254) (xy 0.5334 0.254)
				(xy 0.5334 0.2794)
			)
			(stroke
				(width 0)
				(type default)
			)
			(fill no)
			(layer "F.CrtYd")
		)
		(pad "1" smd rect
			(at 0.40005 0 180)
			(size 0.4572 0.508)
			(layers "F.Cu" "F.Mask" "F.Paste")
			(net "PSU1_REMOTE_R2_P")
		)
		(pad "2" smd rect
			(at -0.40005 0 180)
			(size 0.4572 0.508)
			(layers "F.Cu" "F.Mask" "F.Paste")
			(net "P12V")
		)
	)
)
